FILE_TYPE = MULTI_PHYS_TABLE;
PART 'CONN7_E82125014'
{======================================================================================================================================================================================}
:PACK_TYPE|MATERIAL  |PART_NUMBER      = EnvComp |PART_NUMBER   |JEDEC_TYPE         |CLASS  |DESCRIPTION                                      |COMPONENT_TYPE  |HEIGHT      |LEAD_LENGTH  | SPEED_URL | Status |RPL| AML | Bus_Unit | Days;
{======================================================================================================================================================================================}
'IO'      | 'CONN'   | 'E82125-014'(!) = ''      | 'E82125-014' | 'CONN7_E82125014' | 'IO'  | '(USE SYM 1)CONN,MISC,7P,SATA3,15U",VT,DIP,BLU' | 'THMT'         | '0.358 IN' | '0.106'     | 'http://speed.intel.com:8081/speed/module/pdm/item/pdm_item_detail_direct.asp?item_cde=E82125-014&item_rev=01&url_param=unused' | '' | '' | '' | '' | '' 
'IO'      | 'EMPTY'  | 'E82125-014'(!) = ''      | 'E82125-014' | 'CONN7_E82125014' | 'IO'  | '(USE SYM 1)CONN,MISC,7P,SATA3,15U",VT,DIP,BLU' | 'THMT'         | '0.358 IN' | '0.106'     | 'http://speed.intel.com:8081/speed/module/pdm/item/pdm_item_detail_direct.asp?item_cde=E82125-014&item_rev=01&url_param=unused' | '' | '' | '' | '' | '' 
'TH'      | 'CONN'   | 'E82125-014'(!) = ''      | 'E82125-014' | 'CONN7_E82125014' | 'IO'  | '(USE SYM 2)CONN,MISC,7P,SATA3,15U",VT,DIP,BLU' | 'THMT'         | '0.358 IN' | '0.106'     | 'http://speed.intel.com:8081/speed/module/pdm/item/pdm_item_detail_direct.asp?item_cde=E82125-014&item_rev=01&url_param=unused' | '' | '' | '' | '' | '' 
'TH'      | 'EMPTY'  | 'E82125-014'(!) = ''      | 'E82125-014' | 'CONN7_E82125014' | 'IO'  | '(USE SYM 2)CONN,MISC,7P,SATA3,15U",VT,DIP,BLU' | 'THMT'         | '0.358 IN' | '0.106'     | 'http://speed.intel.com:8081/speed/module/pdm/item/pdm_item_detail_direct.asp?item_cde=E82125-014&item_rev=01&url_param=unused' | '' | '' | '' | '' | '' 
'PIP_IO'  | 'CONN'   | 'E82125-014'(!) = ''      | 'E82125-014' | 'CONN7_E82125014_PIP' | 'IO'  | '(USE SYM 1)CONN,MISC,7P,SATA3,15U",VT,DIP,BLU' | 'THMT'         | '0.358 IN' | '0.106'     | 'http://speed.intel.com:8081/speed/module/pdm/item/pdm_item_detail_direct.asp?item_cde=E82125-014&item_rev=01&url_param=unused' | '' | '' | '' | '' | '' 
'PIP_IO'  | 'EMPTY'  | 'E82125-014'(!) = ''      | 'E82125-014' | 'CONN7_E82125014_PIP' | 'IO'  | '(USE SYM 1)CONN,MISC,7P,SATA3,15U",VT,DIP,BLU' | 'THMT'         | '0.358 IN' | '0.106'     | 'http://speed.intel.com:8081/speed/module/pdm/item/pdm_item_detail_direct.asp?item_cde=E82125-014&item_rev=01&url_param=unused' | '' | '' | '' | '' | '' 
'PIP_TH'  | 'CONN'   | 'E82125-014'(!) = ''      | 'E82125-014' | 'CONN7_E82125014_PIP' | 'IO'  | '(USE SYM 2)CONN,MISC,7P,SATA3,15U",VT,DIP,BLU' | 'THMT'         | '0.358 IN' | '0.106'     | 'http://speed.intel.com:8081/speed/module/pdm/item/pdm_item_detail_direct.asp?item_cde=E82125-014&item_rev=01&url_param=unused' | '' | '' | '' | '' | '' 
'PIP_TH'  | 'EMPTY'  | 'E82125-014'(!) = ''      | 'E82125-014' | 'CONN7_E82125014_PIP' | 'IO'  | '(USE SYM 2)CONN,MISC,7P,SATA3,15U",VT,DIP,BLU' | 'THMT'         | '0.358 IN' | '0.106'     | 'http://speed.intel.com:8081/speed/module/pdm/item/pdm_item_detail_direct.asp?item_cde=E82125-014&item_rev=01&url_param=unused' | '' | '' | '' | '' | ''
END_PART
END.
